FILE_TYPE = MACRO_DRAWING;
SET COLOR_WIRE YELLOW;
SET COLOR_PROP ORANGE;
SET COLOR_DOT WHITE;
SET COLOR_ARC YELLOW;
SET COLOR_BODY GREEN;
SET COLOR_NOTE PURPLE;
SET PROP_DISPLAY VALUE;
SET PAGE_NUMBER P33;
SET PATH_NUMBER P0;
FORCEADD QUANTA_TITLE_BLOCK_C..1
(14525 3850);
FORCEPROP 0 LAST CDS_CON_LAST_MODIFIED Fri Aug 25 17:25:43 2023
J 0
(12640 3865);
DISPLAY INVISIBLE (12640 3865);
FORCEPROP 2 LAST Q_DEPT 
J 1
(10762 3899);
DISPLAY 1.957447 (10762 3899);
PAINT GREEN (10762 3899);
FORCEPROP 1 LAST CUSTOM_TXT_CDS <CON_LAST_MODIFIED>
J 0
(12640 3865);
DISPLAY 0.978723 (12640 3865);
FORCEPROP 2 LAST CUSTOM_TXT_CDS <XR_PAGE_TITLE>
J 0
(6635 9100);
DISPLAY 0.638298 (6635 9100);
PAINT PINK (6635 9100);
DISPLAY INVISIBLE (6635 9100);
FORCEPROP 1 LAST CUSTOM_TXT_CDS <NAME_2>
J 0
(11350 3900);
FORCEPROP 1 LAST CUSTOM_TXT_CDS <NAME_1>
J 0
(11350 4025);
FORCEPROP 1 LAST CUSTOM_TXT_CDS <Q_NUMBER>
J 0
(13122 3953);
DISPLAY 1.212766 (13122 3953);
FORCEPROP 1 LAST CUSTOM_TXT_CDS <Q_PROJ>
J 0
(12143 3952);
DISPLAY 1.212766 (12143 3952);
FORCEPROP 1 LAST CUSTOM_TXT_CDS <Q_REV>
J 0
(14341 3953);
DISPLAY 1.212766 (14341 3953);
FORCEPROP 1 LAST CUSTOM_TXT_CDS <CON_PAGE_NUM> OF <CON_TOTAL_PAGES>
J 0
(14079 3868);
DISPLAY 0.978723 (14079 3868);
FORCEPROP 1 LAST Q_TITLE BLANK PAGE
J 0
(5259 3951);
DISPLAY 2.446809 (5259 3951);
PAINT GREEN (5259 3951);
FORCEPROP 2 LAST CDS_LIB pure_quanta
J 0
(14525 3850);
DISPLAY INVISIBLE (14525 3850);
FORCEPROP 1 LAST CDS_LMAN_SYM_OUTLINE -9475,6775,100,-125
J 0
(14525 3850);
DISPLAY 0.468085 (14525 3850);
PAINT GREEN (14525 3850);
DISPLAY INVISIBLE (14525 3850);
FORCEPROP 2 LAST PAGE_BORDER TRUE
J 0
(6635 9100);
DISPLAY 0.638298 (6635 9100);
PAINT PINK (6635 9100);
DISPLAY INVISIBLE (6635 9100);
FORCEPROP 1 LAST COMMENT_BODY TRUE
J 0
(14537 3837);
DISPLAY 0.978723 (14537 3837);
PAINT PEACH (14537 3837);
DISPLAY INVISIBLE (14537 3837);
FORCEPROP 2 LAST CDS_XR_PAGE_TITLE CR-33 : @SCM_LIB.SCM(SCH_1):PAGE33
J 0
(6635 9100);
DISPLAY 0.638298 (6635 9100);
PAINT PINK (6635 9100);
DISPLAY INVISIBLE (6635 9100);
QUIT
